# T6G (Grand Teton) — schematic netlist excerpt (pin names and nets, part order shuffled) for the footprints in the layout excerpt that follows; sources: Cadence DE-HDL packaged netlist, KiCad conversion of 04192023_DAF0TMB3IC0_F0TG_MB_C_brd_V02_OCP.brd

C356  Q_CAP  0.1UF 16V 10% X7R  pkg C0402  page 83 : A = P3V3_AUX ; B = GND
C2634  Q_CAP  22UF 4V 20% X6S  pkg C0402  page 70 : A = PVDD11_S3_P0 ; B = GND

(kicad_pcb
	(version 20260206)
	(generator "pcbnew")
	(generator_version "10.0")
	(general
		(thickness 1.6)
		(legacy_teardrops no)
	)
	(paper "A4")
	(title_block
		(title "04192023_DAF0TMB3IC0_F0TG_MB_C_brd_V02_OCP.brd")
		(comment 1 "Grand Teton / footprints 7880-7881 of 8354")
	)
	(layers
		(0 "F.Cu" signal "TOP")
		(4 "In1.Cu" signal "GND")
		(6 "In2.Cu" signal "IN1")
		(8 "In3.Cu" signal "GND1")
		(10 "In4.Cu" signal "IN2")
		(12 "In5.Cu" signal "GND2")
		(14 "In6.Cu" signal "IN3")
		(16 "In7.Cu" signal "GND3")
		(18 "In8.Cu" signal "VCC")
		(20 "In9.Cu" signal "VCC1")
		(22 "In10.Cu" signal "GND4")
		(24 "In11.Cu" signal "IN4")
		(26 "In12.Cu" signal "GND5")
		(28 "In13.Cu" signal "IN5")
		(30 "In14.Cu" signal "GND6")
		(32 "In15.Cu" signal "IN6")
		(34 "In16.Cu" signal "GND7")
		(2 "B.Cu" signal "BOTTOM")
		(9 "F.Adhes" user "F.Adhesive")
		(11 "B.Adhes" user "B.Adhesive")
		(13 "F.Paste" user "Package Geometry/Pastemask Top")
		(15 "B.Paste" user "Package Geometry/Pastemask Bottom")
		(5 "F.SilkS" user "Ref Des/Silkscreen Top")
		(7 "B.SilkS" user "Ref Des/Silkscreen Bottom")
		(1 "F.Mask" user "Board Geometry/Soldermask Top")
		(3 "B.Mask" user "Board Geometry/Soldermask Bottom")
		(17 "Dwgs.User" user "User.Drawings")
		(19 "Cmts.User" user "User.Comments")
		(21 "Eco1.User" user "User.Eco1")
		(23 "Eco2.User" user "User.Eco2")
		(25 "Edge.Cuts" user "Board Geometry/Outline")
		(27 "Margin" user)
		(31 "F.CrtYd" user "Package Geometry/Place Bound Top")
		(29 "B.CrtYd" user "Package Geometry/Place Bound Bottom")
		(35 "F.Fab" user "Ref Des/Assembly Top")
		(33 "B.Fab" user "Ref Des/Assembly Bottom")
	)
	(footprint ""
		(layer "B.Cu")
		(at 188.712094 -113.862866)
		(property "Reference" "C356"
			(at 0 0 0)
			(layer "B.SilkS")
			(hide yes)
			(effects
				(font
					(size 1.27 1.27)
				)
				(justify mirror)
			)
		)
		(property "Value" ""
			(at 0 0 0)
			(layer "B.Fab")
			(effects
				(font
					(size 1.27 1.27)
				)
				(justify mirror)
			)
		)
		(duplicate_pad_numbers_are_jumpers no)
		(fp_line
			(start -0.69215 -0.2921)
			(end -0.69215 0.2921)
			(stroke
				(width 0.1524)
				(type default)
			)
			(layer "B.SilkS")
		)
		(fp_line
			(start -0.69215 0.2921)
			(end 0.69215 0.2921)
			(stroke
				(width 0.1524)
				(type default)
			)
			(layer "B.SilkS")
		)
		(fp_line
			(start 0.69215 -0.2921)
			(end -0.69215 -0.2921)
			(stroke
				(width 0.1524)
				(type default)
			)
			(layer "B.SilkS")
		)
		(fp_line
			(start 0.69215 0.2921)
			(end 0.69215 -0.2921)
			(stroke
				(width 0.1524)
				(type default)
			)
			(layer "B.SilkS")
		)
		(fp_line
			(start -0.51435 -0.2794)
			(end -0.51435 0.2794)
			(stroke
				(width 0.1)
				(type default)
			)
			(layer "B.Fab")
		)
		(fp_line
			(start -0.51435 0.2794)
			(end 0.51435 0.2794)
			(stroke
				(width 0.1)
				(type default)
			)
			(layer "B.Fab")
		)
		(fp_line
			(start 0.51435 -0.2794)
			(end -0.51435 -0.2794)
			(stroke
				(width 0.1)
				(type default)
			)
			(layer "B.Fab")
		)
		(fp_line
			(start 0.51435 0.2794)
			(end 0.51435 -0.2794)
			(stroke
				(width 0.1)
				(type default)
			)
			(layer "B.Fab")
		)
		(pad "1" smd circle
			(at 0.40005 0 180)
			(size 0 0)
			(layers "B.Cu" "B.Mask" "B.Paste")
			(net "P3V3_AUX")
		)
		(pad "2" smd circle
			(at -0.40005 0 180)
			(size 0 0)
			(layers "B.Cu" "B.Mask" "B.Paste")
			(net "GND")
		)
		(zone
			(layer "B.Cu")
			(hatch none 0.5)
			(connect_pads
				(clearance 0)
			)
			(min_thickness 0.25)
			(keepout
				(tracks not_allowed)
				(vias allowed)
				(pads allowed)
				(copperpour not_allowed)
				(footprints allowed)
			)
			(placement
				(enabled no)
				(sheetname "")
			)
			(fill
				(thermal_gap 0.5)
				(thermal_bridge_width 0.5)
				(island_removal_mode 0)
			)
			(polygon
				(pts
					(xy 188.521594 -113.775236) (xy 188.521594 -113.950496) (xy 188.611764 -114.008916) (xy 188.811154 -114.008916)
					(xy 188.902594 -113.95075) (xy 188.902594 -113.775236) (xy 188.811154 -113.71707) (xy 188.611764 -113.71707)
				)
			)
		)
	)
	(footprint ""
		(layer "B.Cu")
		(at 362.267246 -261.747762 90)
		(property "Reference" "C2634"
			(at 0 0 90)
			(layer "B.SilkS")
			(hide yes)
			(effects
				(font
					(size 1.27 1.27)
				)
				(justify mirror)
			)
		)
		(property "Value" ""
			(at 0 0 90)
			(layer "B.Fab")
			(effects
				(font
					(size 1.27 1.27)
				)
				(justify mirror)
			)
		)
		(duplicate_pad_numbers_are_jumpers no)
		(fp_line
			(start 0.7874 -0.4064)
			(end -0.7874 -0.4064)
			(stroke
				(width 0.1524)
				(type default)
			)
			(layer "B.SilkS")
		)
		(fp_line
			(start -0.7874 -0.4064)
			(end -0.7874 0.4064)
			(stroke
				(width 0.1524)
				(type default)
			)
			(layer "B.SilkS")
		)
		(fp_line
			(start 0.7874 0.4064)
			(end 0.7874 -0.4064)
			(stroke
				(width 0.1524)
				(type default)
			)
			(layer "B.SilkS")
		)
		(fp_line
			(start -0.7874 0.4064)
			(end 0.7874 0.4064)
			(stroke
				(width 0.1524)
				(type default)
			)
			(layer "B.SilkS")
		)
		(fp_line
			(start 0.67945 -0.305054)
			(end 0.12065 -0.305054)
			(stroke
				(width 0.1)
				(type default)
			)
			(layer "B.Fab")
		)
		(fp_line
			(start 0.12065 -0.305054)
			(end 0.12065 -0.2794)
			(stroke
				(width 0.1)
				(type default)
			)
			(layer "B.Fab")
		)
		(fp_line
			(start -0.12065 -0.3048)
			(end -0.67945 -0.3048)
			(stroke
				(width 0.1)
				(type default)
			)
			(layer "B.Fab")
		)
		(fp_line
			(start -0.67945 -0.3048)
			(end -0.67945 0.3048)
			(stroke
				(width 0.1)
				(type default)
			)
			(layer "B.Fab")
		)
		(fp_line
			(start 0.12065 -0.2794)
			(end -0.12065 -0.2794)
			(stroke
				(width 0.1)
				(type default)
			)
			(layer "B.Fab")
		)
		(fp_line
			(start -0.12065 -0.2794)
			(end -0.12065 -0.3048)
			(stroke
				(width 0.1)
				(type default)
			)
			(layer "B.Fab")
		)
		(fp_line
			(start 0.12065 0.2794)
			(end 0.12065 0.3048)
			(stroke
				(width 0.1)
				(type default)
			)
			(layer "B.Fab")
		)
		(fp_line
			(start -0.120396 0.2794)
			(end 0.12065 0.2794)
			(stroke
				(width 0.1)
				(type default)
			)
			(layer "B.Fab")
		)
		(fp_line
			(start 0.67945 0.3048)
			(end 0.67945 -0.305054)
			(stroke
				(width 0.1)
				(type default)
			)
			(layer "B.Fab")
		)
		(fp_line
			(start 0.12065 0.3048)
			(end 0.67945 0.3048)
			(stroke
				(width 0.1)
				(type default)
			)
			(layer "B.Fab")
		)
		(fp_line
			(start -0.120396 0.3048)
			(end -0.120396 0.2794)
			(stroke
				(width 0.1)
				(type default)
			)
			(layer "B.Fab")
		)
		(fp_line
			(start -0.67945 0.3048)
			(end -0.120396 0.3048)
			(stroke
				(width 0.1)
				(type default)
			)
			(layer "B.Fab")
		)
		(pad "1" smd circle
			(at 0.40005 0 270)
			(size 0 0)
			(layers "B.Cu" "B.Mask" "B.Paste")
			(net "PVDD11_S3_P0")
		)
		(pad "2" smd circle
			(at -0.40005 0 270)
			(size 0 0)
			(layers "B.Cu" "B.Mask" "B.Paste")
			(net "GND")
		)
	)
)
